(kicad_pcb
	(version 20260206)
	(generator "pcbnew")
	(generator_version "10.0")
	(general
		(thickness 1.6)
		(legacy_teardrops no)
	)
	(paper "A4")
	(title_block
		(title "04192023_DAF0TMB3IC0_F0TG_MB_C_brd_V02_OCP.brd")
		(comment 1 "Grand Teton / footprints 1476-1482 of 8354")
	)
	(layers
		(0 "F.Cu" signal "TOP")
		(4 "In1.Cu" signal "GND")
		(6 "In2.Cu" signal "IN1")
		(8 "In3.Cu" signal "GND1")
		(10 "In4.Cu" signal "IN2")
		(12 "In5.Cu" signal "GND2")
		(14 "In6.Cu" signal "IN3")
		(16 "In7.Cu" signal "GND3")
		(18 "In8.Cu" signal "VCC")
		(20 "In9.Cu" signal "VCC1")
		(22 "In10.Cu" signal "GND4")
		(24 "In11.Cu" signal "IN4")
		(26 "In12.Cu" signal "GND5")
		(28 "In13.Cu" signal "IN5")
		(30 "In14.Cu" signal "GND6")
		(32 "In15.Cu" signal "IN6")
		(34 "In16.Cu" signal "GND7")
		(2 "B.Cu" signal "BOTTOM")
		(9 "F.Adhes" user "F.Adhesive")
		(11 "B.Adhes" user "B.Adhesive")
		(13 "F.Paste" user "Package Geometry/Pastemask Top")
		(15 "B.Paste" user "Package Geometry/Pastemask Bottom")
		(5 "F.SilkS" user "Ref Des/Silkscreen Top")
		(7 "B.SilkS" user "Ref Des/Silkscreen Bottom")
		(1 "F.Mask" user "Board Geometry/Soldermask Top")
		(3 "B.Mask" user "Board Geometry/Soldermask Bottom")
		(17 "Dwgs.User" user "User.Drawings")
		(19 "Cmts.User" user "User.Comments")
		(21 "Eco1.User" user "User.Eco1")
		(23 "Eco2.User" user "User.Eco2")
		(25 "Edge.Cuts" user "Board Geometry/Outline")
		(27 "Margin" user)
		(31 "F.CrtYd" user "Package Geometry/Place Bound Top")
		(29 "B.CrtYd" user "Package Geometry/Place Bound Bottom")
		(35 "F.Fab" user "Ref Des/Assembly Top")
		(33 "B.Fab" user "Ref Des/Assembly Bottom")
	)
	(footprint ""
		(layer "F.Cu")
		(at 417.731702 -416.899344 -90)
		(property "Reference" "C6595"
			(at 0 0 270)
			(layer "F.SilkS")
			(hide yes)
			(effects
				(font
					(size 1.27 1.27)
				)
			)
		)
		(property "Value" ""
			(at 0 0 270)
			(layer "F.Fab")
			(effects
				(font
					(size 1.27 1.27)
				)
			)
		)
		(duplicate_pad_numbers_are_jumpers no)
		(fp_line
			(start -0.299974 0.150114)
			(end -0.299974 -0.150114)
			(stroke
				(width 0.1)
				(type default)
			)
			(layer "F.Fab")
		)
		(fp_line
			(start 0.299974 0.150114)
			(end -0.299974 0.150114)
			(stroke
				(width 0.1)
				(type default)
			)
			(layer "F.Fab")
		)
		(fp_line
			(start -0.299974 -0.150114)
			(end 0.299974 -0.150114)
			(stroke
				(width 0.1)
				(type default)
			)
			(layer "F.Fab")
		)
		(fp_line
			(start 0.299974 -0.150114)
			(end 0.299974 0.150114)
			(stroke
				(width 0.1)
				(type default)
			)
			(layer "F.Fab")
		)
		(pad "1" smd rect
			(at -0.2667 0 270)
			(size 0.3048 0.381)
			(layers "F.Cu" "F.Mask" "F.Paste")
			(net "P5E_CPU0_P2_TX_BUF_C_DP<15>")
		)
		(pad "2" smd rect
			(at 0.2667 0 270)
			(size 0.3048 0.381)
			(layers "F.Cu" "F.Mask" "F.Paste")
			(net "P5E_CPU0_P2_TX_BUF_DP<15>")
		)
	)
	(footprint ""
		(layer "F.Cu")
		(at 420.591488 -332.63586 -90)
		(property "Reference" "PC228"
			(at -4.97332 -17.659096 90)
			(unlocked yes)
			(layer "F.SilkS")
			(effects
				(font
					(size 0.7874 0.5842)
					(thickness 0.1524)
				)
				(justify left)
			)
		)
		(property "Value" ""
			(at 0 0 270)
			(layer "F.Fab")
			(effects
				(font
					(size 1.27 1.27)
				)
			)
		)
		(duplicate_pad_numbers_are_jumpers no)
		(fp_line
			(start -1.988058 2.750058)
			(end 2.750058 2.750058)
			(stroke
				(width 0.1524)
				(type default)
			)
			(layer "F.SilkS")
		)
		(fp_line
			(start 2.750058 2.750058)
			(end 2.750058 0.9398)
			(stroke
				(width 0.1524)
				(type default)
			)
			(layer "F.SilkS")
		)
		(fp_line
			(start -2.750058 1.988058)
			(end -1.988058 2.750058)
			(stroke
				(width 0.1524)
				(type default)
			)
			(layer "F.SilkS")
		)
		(fp_line
			(start -2.750058 0.9398)
			(end -2.750058 1.988058)
			(stroke
				(width 0.1524)
				(type default)
			)
			(layer "F.SilkS")
		)
		(fp_line
			(start 2.750058 -0.9398)
			(end 2.750058 -2.750058)
			(stroke
				(width 0.1524)
				(type default)
			)
			(layer "F.SilkS")
		)
		(fp_line
			(start -2.750058 -1.988058)
			(end -2.750058 -0.9398)
			(stroke
				(width 0.1524)
				(type default)
			)
			(layer "F.SilkS")
		)
		(fp_line
			(start -1.988058 -2.750058)
			(end -2.750058 -1.988058)
			(stroke
				(width 0.1524)
				(type default)
			)
			(layer "F.SilkS")
		)
		(fp_line
			(start 2.750058 -2.750058)
			(end -1.988058 -2.750058)
			(stroke
				(width 0.1524)
				(type default)
			)
			(layer "F.SilkS")
		)
		(fp_line
			(start -2.750058 2.750058)
			(end 2.750058 2.750058)
			(stroke
				(width 0.1)
				(type default)
			)
			(layer "F.Fab")
		)
		(fp_line
			(start 2.750058 2.750058)
			(end 2.750058 -2.750058)
			(stroke
				(width 0.1)
				(type default)
			)
			(layer "F.Fab")
		)
		(fp_line
			(start -2.750058 -2.750058)
			(end -2.750058 2.750058)
			(stroke
				(width 0.1)
				(type default)
			)
			(layer "F.Fab")
		)
		(fp_line
			(start 2.750058 -2.750058)
			(end -2.750058 -2.750058)
			(stroke
				(width 0.1)
				(type default)
			)
			(layer "F.Fab")
		)
		(pad "1" smd rect
			(at -2.199894 0)
			(size 1.6002 3.0226)
			(layers "F.Cu" "F.Mask" "F.Paste")
			(net "PVDD11_S3_P0")
		)
		(pad "2" smd rect
			(at 2.199894 0)
			(size 1.6002 3.0226)
			(layers "F.Cu" "F.Mask" "F.Paste")
			(net "GND")
		)
	)
	(footprint ""
		(layer "F.Cu")
		(at 350.421702 -156.281882 -90)
		(property "Reference" "PC150_6"
			(at 0 0 270)
			(layer "F.SilkS")
			(hide yes)
			(effects
				(font
					(size 1.27 1.27)
				)
			)
		)
		(property "Value" ""
			(at 0 0 270)
			(layer "F.Fab")
			(effects
				(font
					(size 1.27 1.27)
				)
			)
		)
		(duplicate_pad_numbers_are_jumpers no)
		(fp_line
			(start -0.7874 0.4064)
			(end -0.7874 -0.4064)
			(stroke
				(width 0.1524)
				(type default)
			)
			(layer "F.SilkS")
		)
		(fp_line
			(start 0.7874 0.4064)
			(end -0.7874 0.4064)
			(stroke
				(width 0.1524)
				(type default)
			)
			(layer "F.SilkS")
		)
		(fp_line
			(start -0.7874 -0.4064)
			(end 0.7874 -0.4064)
			(stroke
				(width 0.1524)
				(type default)
			)
			(layer "F.SilkS")
		)
		(fp_line
			(start 0.7874 -0.4064)
			(end 0.7874 0.4064)
			(stroke
				(width 0.1524)
				(type default)
			)
			(layer "F.SilkS")
		)
		(fp_line
			(start -0.67945 0.3048)
			(end -0.67945 -0.305054)
			(stroke
				(width 0.1)
				(type default)
			)
			(layer "F.Fab")
		)
		(fp_line
			(start -0.12065 0.3048)
			(end -0.67945 0.3048)
			(stroke
				(width 0.1)
				(type default)
			)
			(layer "F.Fab")
		)
		(fp_line
			(start 0.120396 0.3048)
			(end 0.120396 0.2794)
			(stroke
				(width 0.1)
				(type default)
			)
			(layer "F.Fab")
		)
		(fp_line
			(start 0.67945 0.3048)
			(end 0.120396 0.3048)
			(stroke
				(width 0.1)
				(type default)
			)
			(layer "F.Fab")
		)
		(fp_line
			(start -0.12065 0.2794)
			(end -0.12065 0.3048)
			(stroke
				(width 0.1)
				(type default)
			)
			(layer "F.Fab")
		)
		(fp_line
			(start 0.120396 0.2794)
			(end -0.12065 0.2794)
			(stroke
				(width 0.1)
				(type default)
			)
			(layer "F.Fab")
		)
		(fp_line
			(start -0.12065 -0.2794)
			(end 0.12065 -0.2794)
			(stroke
				(width 0.1)
				(type default)
			)
			(layer "F.Fab")
		)
		(fp_line
			(start 0.12065 -0.2794)
			(end 0.12065 -0.3048)
			(stroke
				(width 0.1)
				(type default)
			)
			(layer "F.Fab")
		)
		(fp_line
			(start 0.12065 -0.3048)
			(end 0.67945 -0.3048)
			(stroke
				(width 0.1)
				(type default)
			)
			(layer "F.Fab")
		)
		(fp_line
			(start 0.67945 -0.3048)
			(end 0.67945 0.3048)
			(stroke
				(width 0.1)
				(type default)
			)
			(layer "F.Fab")
		)
		(fp_line
			(start -0.67945 -0.305054)
			(end -0.12065 -0.305054)
			(stroke
				(width 0.1)
				(type default)
			)
			(layer "F.Fab")
		)
		(fp_line
			(start -0.12065 -0.305054)
			(end -0.12065 -0.2794)
			(stroke
				(width 0.1)
				(type default)
			)
			(layer "F.Fab")
		)
		(pad "1" smd circle
			(at -0.40005 0 270)
			(size 0 0)
			(layers "F.Cu" "F.Mask" "F.Paste")
			(net "PVDDCR_CPU0_P0_VCCS")
		)
		(pad "2" smd circle
			(at 0.40005 0 270)
			(size 0 0)
			(layers "F.Cu" "F.Mask" "F.Paste")
			(net "GND")
		)
	)
	(footprint ""
		(layer "F.Cu")
		(at 15.58417 -69.178678)
		(property "Reference" "R3147"
			(at 0 0 0)
			(layer "F.SilkS")
			(hide yes)
			(effects
				(font
					(size 1.27 1.27)
				)
			)
		)
		(property "Value" ""
			(at 0 0 0)
			(layer "F.Fab")
			(effects
				(font
					(size 1.27 1.27)
				)
			)
		)
		(duplicate_pad_numbers_are_jumpers no)
		(fp_line
			(start -0.7874 -0.4064)
			(end 0.7874 -0.4064)
			(stroke
				(width 0.1524)
				(type default)
			)
			(layer "F.SilkS")
		)
		(fp_line
			(start -0.7874 0.4064)
			(end -0.7874 -0.4064)
			(stroke
				(width 0.1524)
				(type default)
			)
			(layer "F.SilkS")
		)
		(fp_line
			(start 0.7874 -0.4064)
			(end 0.7874 0.4064)
			(stroke
				(width 0.1524)
				(type default)
			)
			(layer "F.SilkS")
		)
		(fp_line
			(start 0.7874 0.4064)
			(end -0.7874 0.4064)
			(stroke
				(width 0.1524)
				(type default)
			)
			(layer "F.SilkS")
		)
		(fp_line
			(start -0.67945 -0.305054)
			(end -0.12065 -0.305054)
			(stroke
				(width 0.1)
				(type default)
			)
			(layer "F.Fab")
		)
		(fp_line
			(start -0.67945 0.3048)
			(end -0.67945 -0.305054)
			(stroke
				(width 0.1)
				(type default)
			)
			(layer "F.Fab")
		)
		(fp_line
			(start -0.12065 -0.305054)
			(end -0.12065 -0.2794)
			(stroke
				(width 0.1)
				(type default)
			)
			(layer "F.Fab")
		)
		(fp_line
			(start -0.12065 -0.2794)
			(end 0.12065 -0.2794)
			(stroke
				(width 0.1)
				(type default)
			)
			(layer "F.Fab")
		)
		(fp_line
			(start -0.12065 0.2794)
			(end -0.12065 0.3048)
			(stroke
				(width 0.1)
				(type default)
			)
			(layer "F.Fab")
		)
		(fp_line
			(start -0.12065 0.3048)
			(end -0.67945 0.3048)
			(stroke
				(width 0.1)
				(type default)
			)
			(layer "F.Fab")
		)
		(fp_line
			(start 0.120396 0.2794)
			(end -0.12065 0.2794)
			(stroke
				(width 0.1)
				(type default)
			)
			(layer "F.Fab")
		)
		(fp_line
			(start 0.120396 0.3048)
			(end 0.120396 0.2794)
			(stroke
				(width 0.1)
				(type default)
			)
			(layer "F.Fab")
		)
		(fp_line
			(start 0.12065 -0.3048)
			(end 0.67945 -0.3048)
			(stroke
				(width 0.1)
				(type default)
			)
			(layer "F.Fab")
		)
		(fp_line
			(start 0.12065 -0.2794)
			(end 0.12065 -0.3048)
			(stroke
				(width 0.1)
				(type default)
			)
			(layer "F.Fab")
		)
		(fp_line
			(start 0.67945 -0.3048)
			(end 0.67945 0.3048)
			(stroke
				(width 0.1)
				(type default)
			)
			(layer "F.Fab")
		)
		(fp_line
			(start 0.67945 0.3048)
			(end 0.120396 0.3048)
			(stroke
				(width 0.1)
				(type default)
			)
			(layer "F.Fab")
		)
		(pad "1" smd circle
			(at -0.40005 0)
			(size 0 0)
			(layers "F.Cu" "F.Mask" "F.Paste")
			(net "P3V3_AUX")
		)
		(pad "2" smd circle
			(at 0.40005 0)
			(size 0 0)
			(layers "F.Cu" "F.Mask" "F.Paste")
			(net "HP_LVC3_OCP_V3_2_PRSNT2_PLD_N")
		)
	)
	(footprint ""
		(layer "F.Cu")
		(at 190.94958 -413.964882 -90)
		(property "Reference" "R2941"
			(at 0 0 270)
			(layer "F.SilkS")
			(hide yes)
			(effects
				(font
					(size 1.27 1.27)
				)
			)
		)
		(property "Value" ""
			(at 0 0 270)
			(layer "F.Fab")
			(effects
				(font
					(size 1.27 1.27)
				)
			)
		)
		(duplicate_pad_numbers_are_jumpers no)
		(fp_line
			(start -0.7874 0.4064)
			(end -0.7874 -0.4064)
			(stroke
				(width 0.1524)
				(type default)
			)
			(layer "F.SilkS")
		)
		(fp_line
			(start 0.7874 0.4064)
			(end -0.7874 0.4064)
			(stroke
				(width 0.1524)
				(type default)
			)
			(layer "F.SilkS")
		)
		(fp_line
			(start -0.7874 -0.4064)
			(end 0.7874 -0.4064)
			(stroke
				(width 0.1524)
				(type default)
			)
			(layer "F.SilkS")
		)
		(fp_line
			(start 0.7874 -0.4064)
			(end 0.7874 0.4064)
			(stroke
				(width 0.1524)
				(type default)
			)
			(layer "F.SilkS")
		)
		(fp_line
			(start -0.67945 0.3048)
			(end -0.67945 -0.305054)
			(stroke
				(width 0.1)
				(type default)
			)
			(layer "F.Fab")
		)
		(fp_line
			(start -0.12065 0.3048)
			(end -0.67945 0.3048)
			(stroke
				(width 0.1)
				(type default)
			)
			(layer "F.Fab")
		)
		(fp_line
			(start 0.120396 0.3048)
			(end 0.120396 0.2794)
			(stroke
				(width 0.1)
				(type default)
			)
			(layer "F.Fab")
		)
		(fp_line
			(start 0.67945 0.3048)
			(end 0.120396 0.3048)
			(stroke
				(width 0.1)
				(type default)
			)
			(layer "F.Fab")
		)
		(fp_line
			(start -0.12065 0.2794)
			(end -0.12065 0.3048)
			(stroke
				(width 0.1)
				(type default)
			)
			(layer "F.Fab")
		)
		(fp_line
			(start 0.120396 0.2794)
			(end -0.12065 0.2794)
			(stroke
				(width 0.1)
				(type default)
			)
			(layer "F.Fab")
		)
		(fp_line
			(start -0.12065 -0.2794)
			(end 0.12065 -0.2794)
			(stroke
				(width 0.1)
				(type default)
			)
			(layer "F.Fab")
		)
		(fp_line
			(start 0.12065 -0.2794)
			(end 0.12065 -0.3048)
			(stroke
				(width 0.1)
				(type default)
			)
			(layer "F.Fab")
		)
		(fp_line
			(start 0.12065 -0.3048)
			(end 0.67945 -0.3048)
			(stroke
				(width 0.1)
				(type default)
			)
			(layer "F.Fab")
		)
		(fp_line
			(start 0.67945 -0.3048)
			(end 0.67945 0.3048)
			(stroke
				(width 0.1)
				(type default)
			)
			(layer "F.Fab")
		)
		(fp_line
			(start -0.67945 -0.305054)
			(end -0.12065 -0.305054)
			(stroke
				(width 0.1)
				(type default)
			)
			(layer "F.Fab")
		)
		(fp_line
			(start -0.12065 -0.305054)
			(end -0.12065 -0.2794)
			(stroke
				(width 0.1)
				(type default)
			)
			(layer "F.Fab")
		)
		(pad "1" smd circle
			(at -0.40005 0 270)
			(size 0 0)
			(layers "F.Cu" "F.Mask" "F.Paste")
			(net "FM_GPU_HSC_EN")
		)
		(pad "2" smd circle
			(at 0.40005 0 270)
			(size 0 0)
			(layers "F.Cu" "F.Mask" "F.Paste")
			(net "GND")
		)
	)
	(footprint ""
		(layer "F.Cu")
		(at 253.340108 -107.855004)
		(property "Reference" "U218"
			(at -1.4351 2.394712 0)
			(unlocked yes)
			(layer "F.SilkS")
			(effects
				(font
					(size 0.7874 0.5842)
					(thickness 0.1524)
				)
				(justify left)
			)
		)
		(property "Value" ""
			(at 0 0 0)
			(layer "F.Fab")
			(effects
				(font
					(size 1.27 1.27)
				)
			)
		)
		(duplicate_pad_numbers_are_jumpers no)
		(fp_line
			(start -1.733296 -1.549908)
			(end -1.733296 1.549908)
			(stroke
				(width 0.1524)
				(type default)
			)
			(layer "F.SilkS")
		)
		(fp_line
			(start -1.733296 1.549908)
			(end 1.733296 1.549908)
			(stroke
				(width 0.1524)
				(type default)
			)
			(layer "F.SilkS")
		)
		(fp_line
			(start -0.660908 -1.549908)
			(end -1.733296 -1.549908)
			(stroke
				(width 0.1524)
				(type default)
			)
			(layer "F.SilkS")
		)
		(fp_line
			(start 0 -0.889)
			(end -0.660908 -1.549908)
			(stroke
				(width 0.1524)
				(type default)
			)
			(layer "F.SilkS")
		)
		(fp_line
			(start 0.660908 -1.549908)
			(end 0 -0.889)
			(stroke
				(width 0.1524)
				(type default)
			)
			(layer "F.SilkS")
		)
		(fp_line
			(start 1.733296 -1.549908)
			(end 0.660908 -1.549908)
			(stroke
				(width 0.1524)
				(type default)
			)
			(layer "F.SilkS")
		)
		(fp_line
			(start 1.733296 1.549908)
			(end 1.733296 -1.549908)
			(stroke
				(width 0.1524)
				(type default)
			)
			(layer "F.SilkS")
		)
		(fp_poly
			(pts
				(xy -1.172464 -1.626108) (xy -1.426464 -2.134108) (xy -0.918464 -2.134108)
			)
			(stroke
				(width 0)
				(type default)
			)
			(fill yes)
			(layer "F.SilkS")
		)
		(fp_line
			(start -0.849884 -1.549908)
			(end -0.849884 1.549908)
			(stroke
				(width 0.1)
				(type default)
			)
			(layer "F.Fab")
		)
		(fp_line
			(start -0.849884 1.549908)
			(end 0.849884 1.549908)
			(stroke
				(width 0.1)
				(type default)
			)
			(layer "F.Fab")
		)
		(fp_line
			(start 0.849884 -1.549908)
			(end -0.849884 -1.549908)
			(stroke
				(width 0.1)
				(type default)
			)
			(layer "F.Fab")
		)
		(fp_line
			(start 0.849884 1.549908)
			(end 0.849884 -1.549908)
			(stroke
				(width 0.1)
				(type default)
			)
			(layer "F.Fab")
		)
		(fp_poly
			(pts
				(xy -2.4384 -1.20396) (xy -2.4384 -0.69596) (xy -1.9304 -0.94996)
			)
			(stroke
				(width 0)
				(type default)
			)
			(fill yes)
			(layer "F.Fab")
		)
		(pad "1" smd rect
			(at -1.199896 -0.94996 270)
			(size 0.5588 0.8128)
			(layers "F.Cu" "F.Mask" "F.Paste")
			(net "NC_U218_NC1")
		)
		(pad "2" smd rect
			(at -1.199896 0 270)
			(size 0.5588 0.8128)
			(layers "F.Cu" "F.Mask" "F.Paste")
			(net "FM_SYS_THROTTLE_N")
		)
		(pad "3" smd rect
			(at -1.199896 0.94996 270)
			(size 0.5588 0.8128)
			(layers "F.Cu" "F.Mask" "F.Paste")
			(net "GND")
		)
		(pad "4" smd rect
			(at 1.199896 0.94996 270)
			(size 0.5588 0.8128)
			(layers "F.Cu" "F.Mask" "F.Paste")
			(net "OCP_V3_2_PWRBRK_BUFF_N")
		)
		(pad "5" smd rect
			(at 1.199896 -0.94996 270)
			(size 0.5588 0.8128)
			(layers "F.Cu" "F.Mask" "F.Paste")
			(net "P3V3_AUX")
		)
	)
	(footprint ""
		(layer "F.Cu")
		(at 118.999 -435.102 -90)
		(property "Reference" "C1979"
			(at 0 0 270)
			(layer "F.SilkS")
			(hide yes)
			(effects
				(font
					(size 1.27 1.27)
				)
			)
		)
		(property "Value" ""
			(at 0 0 270)
			(layer "F.Fab")
			(effects
				(font
					(size 1.27 1.27)
				)
			)
		)
		(duplicate_pad_numbers_are_jumpers no)
		(fp_line
			(start -0.7874 0.4064)
			(end -0.7874 -0.4064)
			(stroke
				(width 0.1524)
				(type default)
			)
			(layer "F.SilkS")
		)
		(fp_line
			(start 0.7874 0.4064)
			(end -0.7874 0.4064)
			(stroke
				(width 0.1524)
				(type default)
			)
			(layer "F.SilkS")
		)
		(fp_line
			(start -0.7874 -0.4064)
			(end 0.7874 -0.4064)
			(stroke
				(width 0.1524)
				(type default)
			)
			(layer "F.SilkS")
		)
		(fp_line
			(start 0.7874 -0.4064)
			(end 0.7874 0.4064)
			(stroke
				(width 0.1524)
				(type default)
			)
			(layer "F.SilkS")
		)
		(fp_line
			(start -0.67945 0.3048)
			(end -0.67945 -0.305054)
			(stroke
				(width 0.1)
				(type default)
			)
			(layer "F.Fab")
		)
		(fp_line
			(start -0.12065 0.3048)
			(end -0.67945 0.3048)
			(stroke
				(width 0.1)
				(type default)
			)
			(layer "F.Fab")
		)
		(fp_line
			(start 0.120396 0.3048)
			(end 0.120396 0.2794)
			(stroke
				(width 0.1)
				(type default)
			)
			(layer "F.Fab")
		)
		(fp_line
			(start 0.67945 0.3048)
			(end 0.120396 0.3048)
			(stroke
				(width 0.1)
				(type default)
			)
			(layer "F.Fab")
		)
		(fp_line
			(start -0.12065 0.2794)
			(end -0.12065 0.3048)
			(stroke
				(width 0.1)
				(type default)
			)
			(layer "F.Fab")
		)
		(fp_line
			(start 0.120396 0.2794)
			(end -0.12065 0.2794)
			(stroke
				(width 0.1)
				(type default)
			)
			(layer "F.Fab")
		)
		(fp_line
			(start -0.12065 -0.2794)
			(end 0.12065 -0.2794)
			(stroke
				(width 0.1)
				(type default)
			)
			(layer "F.Fab")
		)
		(fp_line
			(start 0.12065 -0.2794)
			(end 0.12065 -0.3048)
			(stroke
				(width 0.1)
				(type default)
			)
			(layer "F.Fab")
		)
		(fp_line
			(start 0.12065 -0.3048)
			(end 0.67945 -0.3048)
			(stroke
				(width 0.1)
				(type default)
			)
			(layer "F.Fab")
		)
		(fp_line
			(start 0.67945 -0.3048)
			(end 0.67945 0.3048)
			(stroke
				(width 0.1)
				(type default)
			)
			(layer "F.Fab")
		)
		(fp_line
			(start -0.67945 -0.305054)
			(end -0.12065 -0.305054)
			(stroke
				(width 0.1)
				(type default)
			)
			(layer "F.Fab")
		)
		(fp_line
			(start -0.12065 -0.305054)
			(end -0.12065 -0.2794)
			(stroke
				(width 0.1)
				(type default)
			)
			(layer "F.Fab")
		)
		(pad "1" smd circle
			(at -0.40005 0 270)
			(size 0 0)
			(layers "F.Cu" "F.Mask" "F.Paste")
			(net "P3V3_AUX")
		)
		(pad "2" smd circle
			(at 0.40005 0 270)
			(size 0 0)
			(layers "F.Cu" "F.Mask" "F.Paste")
			(net "GND")
		)
	)
)
